# T6G (Grand Teton) — schematic netlist excerpt (pin names and nets, part order shuffled) for the footprints in the layout excerpt that follows; sources: Cadence DE-HDL packaged netlist, KiCad conversion of 04192023_DAF0TMB3IC0_F0TG_MB_C_brd_V02_OCP.brd

R11  Q_RES  10K 1% CHIP  pkg 0402LF  page 83 : A = FM_I3C_CPU0_MUX1_OE_N ; B = GND
C1988  Q_CAP  0.1UF 25V 10% X7R  pkg 0402  page 126 : A = GPU_FPGA_EROT_FATALERR_ISO_N ; B = GND
PC311_5  Q_CAP  22UF 16V 20% X6S  pkg C0805  page 213 : A = SW_P12V_AUX_PVDDCR_CPU0_P1_FLT ; B = GND

(kicad_pcb
	(version 20260206)
	(generator "pcbnew")
	(generator_version "10.0")
	(general
		(thickness 1.6)
		(legacy_teardrops no)
	)
	(paper "A4")
	(title_block
		(title "04192023_DAF0TMB3IC0_F0TG_MB_C_brd_V02_OCP.brd")
		(comment 1 "Grand Teton / footprints 7966-7968 of 8354")
	)
	(layers
		(0 "F.Cu" signal "TOP")
		(4 "In1.Cu" signal "GND")
		(6 "In2.Cu" signal "IN1")
		(8 "In3.Cu" signal "GND1")
		(10 "In4.Cu" signal "IN2")
		(12 "In5.Cu" signal "GND2")
		(14 "In6.Cu" signal "IN3")
		(16 "In7.Cu" signal "GND3")
		(18 "In8.Cu" signal "VCC")
		(20 "In9.Cu" signal "VCC1")
		(22 "In10.Cu" signal "GND4")
		(24 "In11.Cu" signal "IN4")
		(26 "In12.Cu" signal "GND5")
		(28 "In13.Cu" signal "IN5")
		(30 "In14.Cu" signal "GND6")
		(32 "In15.Cu" signal "IN6")
		(34 "In16.Cu" signal "GND7")
		(2 "B.Cu" signal "BOTTOM")
		(9 "F.Adhes" user "F.Adhesive")
		(11 "B.Adhes" user "B.Adhesive")
		(13 "F.Paste" user "Package Geometry/Pastemask Top")
		(15 "B.Paste" user "Package Geometry/Pastemask Bottom")
		(5 "F.SilkS" user "Ref Des/Silkscreen Top")
		(7 "B.SilkS" user "Ref Des/Silkscreen Bottom")
		(1 "F.Mask" user "Board Geometry/Soldermask Top")
		(3 "B.Mask" user "Board Geometry/Soldermask Bottom")
		(17 "Dwgs.User" user "User.Drawings")
		(19 "Cmts.User" user "User.Comments")
		(21 "Eco1.User" user "User.Eco1")
		(23 "Eco2.User" user "User.Eco2")
		(25 "Edge.Cuts" user "Board Geometry/Outline")
		(27 "Margin" user)
		(31 "F.CrtYd" user "Package Geometry/Place Bound Top")
		(29 "B.CrtYd" user "Package Geometry/Place Bound Bottom")
		(35 "F.Fab" user "Ref Des/Assembly Top")
		(33 "B.Fab" user "Ref Des/Assembly Bottom")
	)
	(footprint ""
		(layer "B.Cu")
		(at 72.908668 -177.513234 -90)
		(property "Reference" "PC311_5"
			(at 0 0 90)
			(layer "B.SilkS")
			(hide yes)
			(effects
				(font
					(size 1.27 1.27)
				)
				(justify mirror)
			)
		)
		(property "Value" ""
			(at 0 0 90)
			(layer "B.Fab")
			(effects
				(font
					(size 1.27 1.27)
				)
				(justify mirror)
			)
		)
		(duplicate_pad_numbers_are_jumpers no)
		(fp_line
			(start -1.524 0.762)
			(end 1.524 0.762)
			(stroke
				(width 0.1524)
				(type default)
			)
			(layer "B.SilkS")
		)
		(fp_line
			(start 1.524 0.762)
			(end 1.524 -0.762)
			(stroke
				(width 0.1524)
				(type default)
			)
			(layer "B.SilkS")
		)
		(fp_line
			(start -1.524 -0.762)
			(end -1.524 0.762)
			(stroke
				(width 0.1524)
				(type default)
			)
			(layer "B.SilkS")
		)
		(fp_line
			(start 1.524 -0.762)
			(end -1.524 -0.762)
			(stroke
				(width 0.1524)
				(type default)
			)
			(layer "B.SilkS")
		)
		(fp_line
			(start -1.1049 0.724916)
			(end -1.1049 -0.724916)
			(stroke
				(width 0.1)
				(type default)
			)
			(layer "B.Fab")
		)
		(fp_line
			(start 1.1049 0.724916)
			(end -1.1049 0.724916)
			(stroke
				(width 0.1)
				(type default)
			)
			(layer "B.Fab")
		)
		(fp_line
			(start -1.1049 -0.724916)
			(end 1.1049 -0.724916)
			(stroke
				(width 0.1)
				(type default)
			)
			(layer "B.Fab")
		)
		(fp_line
			(start 1.1049 -0.724916)
			(end 1.1049 0.724916)
			(stroke
				(width 0.1)
				(type default)
			)
			(layer "B.Fab")
		)
		(pad "1" smd rect
			(at 0.889 0 270)
			(size 1.016 1.27)
			(layers "B.Cu" "B.Mask" "B.Paste")
			(net "SW_P12V_AUX_PVDDCR_CPU0_P1_FLT")
		)
		(pad "2" smd rect
			(at -0.889 0 270)
			(size 1.016 1.27)
			(layers "B.Cu" "B.Mask" "B.Paste")
			(net "GND")
		)
	)
	(footprint ""
		(layer "B.Cu")
		(at 167.39743 -105.755694 90)
		(property "Reference" "R11"
			(at 0 0 90)
			(layer "B.SilkS")
			(hide yes)
			(effects
				(font
					(size 1.27 1.27)
				)
				(justify mirror)
			)
		)
		(property "Value" ""
			(at 0 0 90)
			(layer "B.Fab")
			(effects
				(font
					(size 1.27 1.27)
				)
				(justify mirror)
			)
		)
		(duplicate_pad_numbers_are_jumpers no)
		(fp_line
			(start 0.7874 -0.4064)
			(end -0.7874 -0.4064)
			(stroke
				(width 0.1524)
				(type default)
			)
			(layer "B.SilkS")
		)
		(fp_line
			(start -0.7874 -0.4064)
			(end -0.7874 0.4064)
			(stroke
				(width 0.1524)
				(type default)
			)
			(layer "B.SilkS")
		)
		(fp_line
			(start 0.7874 0.4064)
			(end 0.7874 -0.4064)
			(stroke
				(width 0.1524)
				(type default)
			)
			(layer "B.SilkS")
		)
		(fp_line
			(start -0.7874 0.4064)
			(end 0.7874 0.4064)
			(stroke
				(width 0.1524)
				(type default)
			)
			(layer "B.SilkS")
		)
		(fp_line
			(start 0.67945 -0.305054)
			(end 0.12065 -0.305054)
			(stroke
				(width 0.1)
				(type default)
			)
			(layer "B.Fab")
		)
		(fp_line
			(start 0.12065 -0.305054)
			(end 0.12065 -0.2794)
			(stroke
				(width 0.1)
				(type default)
			)
			(layer "B.Fab")
		)
		(fp_line
			(start -0.12065 -0.3048)
			(end -0.67945 -0.3048)
			(stroke
				(width 0.1)
				(type default)
			)
			(layer "B.Fab")
		)
		(fp_line
			(start -0.67945 -0.3048)
			(end -0.67945 0.3048)
			(stroke
				(width 0.1)
				(type default)
			)
			(layer "B.Fab")
		)
		(fp_line
			(start 0.12065 -0.2794)
			(end -0.12065 -0.2794)
			(stroke
				(width 0.1)
				(type default)
			)
			(layer "B.Fab")
		)
		(fp_line
			(start -0.12065 -0.2794)
			(end -0.12065 -0.3048)
			(stroke
				(width 0.1)
				(type default)
			)
			(layer "B.Fab")
		)
		(fp_line
			(start 0.12065 0.2794)
			(end 0.12065 0.3048)
			(stroke
				(width 0.1)
				(type default)
			)
			(layer "B.Fab")
		)
		(fp_line
			(start -0.120396 0.2794)
			(end 0.12065 0.2794)
			(stroke
				(width 0.1)
				(type default)
			)
			(layer "B.Fab")
		)
		(fp_line
			(start 0.67945 0.3048)
			(end 0.67945 -0.305054)
			(stroke
				(width 0.1)
				(type default)
			)
			(layer "B.Fab")
		)
		(fp_line
			(start 0.12065 0.3048)
			(end 0.67945 0.3048)
			(stroke
				(width 0.1)
				(type default)
			)
			(layer "B.Fab")
		)
		(fp_line
			(start -0.120396 0.3048)
			(end -0.120396 0.2794)
			(stroke
				(width 0.1)
				(type default)
			)
			(layer "B.Fab")
		)
		(fp_line
			(start -0.67945 0.3048)
			(end -0.120396 0.3048)
			(stroke
				(width 0.1)
				(type default)
			)
			(layer "B.Fab")
		)
		(pad "1" smd circle
			(at 0.40005 0 270)
			(size 0 0)
			(layers "B.Cu" "B.Mask" "B.Paste")
			(net "FM_I3C_CPU0_MUX1_OE_N")
		)
		(pad "2" smd circle
			(at -0.40005 0 270)
			(size 0 0)
			(layers "B.Cu" "B.Mask" "B.Paste")
			(net "GND")
		)
	)
	(footprint ""
		(layer "B.Cu")
		(at 116.116354 -415.910268 90)
		(property "Reference" "C1988"
			(at 0 0 90)
			(layer "B.SilkS")
			(hide yes)
			(effects
				(font
					(size 1.27 1.27)
				)
				(justify mirror)
			)
		)
		(property "Value" ""
			(at 0 0 90)
			(layer "B.Fab")
			(effects
				(font
					(size 1.27 1.27)
				)
				(justify mirror)
			)
		)
		(duplicate_pad_numbers_are_jumpers no)
		(fp_line
			(start 0.7874 -0.4064)
			(end -0.7874 -0.4064)
			(stroke
				(width 0.1524)
				(type default)
			)
			(layer "B.SilkS")
		)
		(fp_line
			(start -0.7874 -0.4064)
			(end -0.7874 0.4064)
			(stroke
				(width 0.1524)
				(type default)
			)
			(layer "B.SilkS")
		)
		(fp_line
			(start 0.7874 0.4064)
			(end 0.7874 -0.4064)
			(stroke
				(width 0.1524)
				(type default)
			)
			(layer "B.SilkS")
		)
		(fp_line
			(start -0.7874 0.4064)
			(end 0.7874 0.4064)
			(stroke
				(width 0.1524)
				(type default)
			)
			(layer "B.SilkS")
		)
		(fp_line
			(start 0.67945 -0.305054)
			(end 0.12065 -0.305054)
			(stroke
				(width 0.1)
				(type default)
			)
			(layer "B.Fab")
		)
		(fp_line
			(start 0.12065 -0.305054)
			(end 0.12065 -0.2794)
			(stroke
				(width 0.1)
				(type default)
			)
			(layer "B.Fab")
		)
		(fp_line
			(start -0.12065 -0.3048)
			(end -0.67945 -0.3048)
			(stroke
				(width 0.1)
				(type default)
			)
			(layer "B.Fab")
		)
		(fp_line
			(start -0.67945 -0.3048)
			(end -0.67945 0.3048)
			(stroke
				(width 0.1)
				(type default)
			)
			(layer "B.Fab")
		)
		(fp_line
			(start 0.12065 -0.2794)
			(end -0.12065 -0.2794)
			(stroke
				(width 0.1)
				(type default)
			)
			(layer "B.Fab")
		)
		(fp_line
			(start -0.12065 -0.2794)
			(end -0.12065 -0.3048)
			(stroke
				(width 0.1)
				(type default)
			)
			(layer "B.Fab")
		)
		(fp_line
			(start 0.12065 0.2794)
			(end 0.12065 0.3048)
			(stroke
				(width 0.1)
				(type default)
			)
			(layer "B.Fab")
		)
		(fp_line
			(start -0.120396 0.2794)
			(end 0.12065 0.2794)
			(stroke
				(width 0.1)
				(type default)
			)
			(layer "B.Fab")
		)
		(fp_line
			(start 0.67945 0.3048)
			(end 0.67945 -0.305054)
			(stroke
				(width 0.1)
				(type default)
			)
			(layer "B.Fab")
		)
		(fp_line
			(start 0.12065 0.3048)
			(end 0.67945 0.3048)
			(stroke
				(width 0.1)
				(type default)
			)
			(layer "B.Fab")
		)
		(fp_line
			(start -0.120396 0.3048)
			(end -0.120396 0.2794)
			(stroke
				(width 0.1)
				(type default)
			)
			(layer "B.Fab")
		)
		(fp_line
			(start -0.67945 0.3048)
			(end -0.120396 0.3048)
			(stroke
				(width 0.1)
				(type default)
			)
			(layer "B.Fab")
		)
		(pad "1" smd circle
			(at 0.40005 0 270)
			(size 0 0)
			(layers "B.Cu" "B.Mask" "B.Paste")
			(net "GPU_FPGA_EROT_FATALERR_ISO_N")
		)
		(pad "2" smd circle
			(at -0.40005 0 270)
			(size 0 0)
			(layers "B.Cu" "B.Mask" "B.Paste")
			(net "GND")
		)
	)
)
